(kicad_pcb
	(version 20260206)
	(generator "pcbnew")
	(generator_version "10.0")
	(general
		(thickness 1.6)
		(legacy_teardrops no)
	)
	(paper "A4")
	(title_block
		(title "v2-pdb — ms_pdb_v2.brd")
		(comment 1 "Open CloudServer (Microsoft) / footprint 330 of 348 (J7), pads 1-46 of 46")
	)
	(layers
		(0 "F.Cu" signal "TOP")
		(4 "In1.Cu" signal "GND")
		(6 "In2.Cu" signal "IN1")
		(8 "In3.Cu" signal "VCC")
		(10 "In4.Cu" signal "VCC1")
		(12 "In5.Cu" signal "IN2")
		(14 "In6.Cu" signal "GND1")
		(2 "B.Cu" signal "BOTTOM")
		(9 "F.Adhes" user "F.Adhesive")
		(11 "B.Adhes" user "B.Adhesive")
		(13 "F.Paste" user "Package Geometry/Pastemask Top")
		(15 "B.Paste" user "Package Geometry/Pastemask Bottom")
		(5 "F.SilkS" user "Ref Des/Silkscreen Top")
		(7 "B.SilkS" user "Ref Des/Silkscreen Bottom")
		(1 "F.Mask" user "Board Geometry/Soldermask Top")
		(3 "B.Mask" user "Board Geometry/Soldermask Bottom")
		(17 "Dwgs.User" user "User.Drawings")
		(19 "Cmts.User" user "User.Comments")
		(21 "Eco1.User" user "User.Eco1")
		(23 "Eco2.User" user "User.Eco2")
		(25 "Edge.Cuts" user "Board Geometry/Outline")
		(27 "Margin" user)
		(31 "F.CrtYd" user "Package Geometry/Place Bound Top")
		(29 "B.CrtYd" user "Package Geometry/Place Bound Bottom")
		(35 "F.Fab" user "Ref Des/Assembly Top")
		(33 "B.Fab" user "Ref Des/Assembly Bottom")
	)
	(footprint ""
		(layer "B.Cu")
		(at 44.03979 -8.26008 90)
		(property "Reference" "J7"
			(at 6.1214 -5.060442 0)
			(unlocked yes)
			(layer "B.SilkS")
			(effects
				(font
					(size 0.7874 0.5842)
					(thickness 0.1524)
				)
				(justify left mirror)
			)
		)
		(property "Value" ""
			(at 0 0 90)
			(layer "B.Fab")
			(effects
				(font
					(size 1.27 1.27)
				)
				(justify mirror)
			)
		)
		(duplicate_pad_numbers_are_jumpers no)
		(pad "" np_thru_hole circle
			(at -1.35001 -2.54)
			(size 2.5146 2.5146)
			(drill 2.5146)
			(layers "*.Cu" "*.Mask")
			(clearance 0.381)
			(thermal_gap 0.381)
		)
		(pad "" np_thru_hole circle
			(at 0 50.8)
			(size 2.5146 2.5146)
			(drill 2.5146)
			(layers "*.Cu" "*.Mask")
			(clearance 0.381)
			(thermal_gap 0.381)
		)
		(pad "P1" thru_hole rect
			(at 0 0)
			(size 1.1684 1.1684)
			(drill 0.762)
			(layers "*.Cu" "*.Mask")
			(remove_unused_layers no)
			(net "GND")
			(clearance 0.0508)
			(padstack
				(mode front_inner_back)
				(layer "Inner"
					(shape circle)
					(size 1.1684 1.1684)
					(clearance 0.0508)
				)
				(layer "B.Cu"
					(shape rect)
					(size 1.1684 1.1684)
					(thermal_gap 0.0508)
					(clearance 0.0508)
				)
			)
		)
		(pad "P2" thru_hole circle
			(at 0 2.54)
			(size 1.1684 1.1684)
			(drill 0.762)
			(layers "*.Cu" "*.Mask")
			(remove_unused_layers no)
			(net "GND")
			(clearance 0.0508)
			(thermal_gap 0.0508)
		)
		(pad "P3" thru_hole circle
			(at 0 5.08)
			(size 1.1684 1.1684)
			(drill 0.762)
			(layers "*.Cu" "*.Mask")
			(remove_unused_layers no)
			(net "GND")
			(clearance 0.0508)
			(thermal_gap 0.0508)
		)
		(pad "P4" thru_hole circle
			(at 0 7.62)
			(size 1.1684 1.1684)
			(drill 0.762)
			(layers "*.Cu" "*.Mask")
			(remove_unused_layers no)
			(net "GND")
			(clearance 0.0508)
			(thermal_gap 0.0508)
		)
		(pad "P5" thru_hole circle
			(at 0 10.16)
			(size 1.1684 1.1684)
			(drill 0.762)
			(layers "*.Cu" "*.Mask")
			(remove_unused_layers no)
			(net "GND")
			(clearance 0.0508)
			(thermal_gap 0.0508)
		)
		(pad "P6" thru_hole circle
			(at 0 12.7)
			(size 1.1684 1.1684)
			(drill 0.762)
			(layers "*.Cu" "*.Mask")
			(remove_unused_layers no)
			(net "GND")
			(clearance 0.0508)
			(thermal_gap 0.0508)
		)
		(pad "P7" thru_hole circle
			(at 0 15.24)
			(size 1.1684 1.1684)
			(drill 0.762)
			(layers "*.Cu" "*.Mask")
			(remove_unused_layers no)
			(net "GND")
			(clearance 0.0508)
			(thermal_gap 0.0508)
		)
		(pad "P8" thru_hole circle
			(at 0 17.78)
			(size 1.1684 1.1684)
			(drill 0.762)
			(layers "*.Cu" "*.Mask")
			(remove_unused_layers no)
			(net "GND")
			(clearance 0.0508)
			(thermal_gap 0.0508)
		)
		(pad "P9" thru_hole circle
			(at 0 20.32)
			(size 1.1684 1.1684)
			(drill 0.762)
			(layers "*.Cu" "*.Mask")
			(remove_unused_layers no)
			(net "P12V")
			(clearance 0.0508)
			(thermal_gap 0.0508)
		)
		(pad "P10" thru_hole circle
			(at 0 22.86)
			(size 1.1684 1.1684)
			(drill 0.762)
			(layers "*.Cu" "*.Mask")
			(remove_unused_layers no)
			(net "P12V")
			(clearance 0.0508)
			(thermal_gap 0.0508)
		)
		(pad "P11" thru_hole circle
			(at 0 25.4)
			(size 1.1684 1.1684)
			(drill 0.762)
			(layers "*.Cu" "*.Mask")
			(remove_unused_layers no)
			(net "P12V")
			(clearance 0.0508)
			(thermal_gap 0.0508)
		)
		(pad "P12" thru_hole circle
			(at 0 27.94)
			(size 1.1684 1.1684)
			(drill 0.762)
			(layers "*.Cu" "*.Mask")
			(remove_unused_layers no)
			(net "P12V")
			(clearance 0.0508)
			(thermal_gap 0.0508)
		)
		(pad "P13" thru_hole circle
			(at 0 30.48)
			(size 1.1684 1.1684)
			(drill 0.762)
			(layers "*.Cu" "*.Mask")
			(remove_unused_layers no)
			(net "P12V")
			(clearance 0.0508)
			(thermal_gap 0.0508)
		)
		(pad "P14" thru_hole circle
			(at 0 33.02)
			(size 1.1684 1.1684)
			(drill 0.762)
			(layers "*.Cu" "*.Mask")
			(remove_unused_layers no)
			(net "P12V")
			(clearance 0.0508)
			(thermal_gap 0.0508)
		)
		(pad "P15" thru_hole circle
			(at 0 35.56)
			(size 1.1684 1.1684)
			(drill 0.762)
			(layers "*.Cu" "*.Mask")
			(remove_unused_layers no)
			(net "P12V")
			(clearance 0.0508)
			(thermal_gap 0.0508)
		)
		(pad "P16" thru_hole circle
			(at 0 38.1)
			(size 1.1684 1.1684)
			(drill 0.762)
			(layers "*.Cu" "*.Mask")
			(remove_unused_layers no)
			(net "P12V")
			(clearance 0.0508)
			(thermal_gap 0.0508)
		)
		(pad "P17" thru_hole circle
			(at -2.70002 38.1)
			(size 1.1684 1.1684)
			(drill 0.762)
			(layers "*.Cu" "*.Mask")
			(remove_unused_layers no)
			(net "P12V")
			(clearance 0.0508)
			(thermal_gap 0.0508)
		)
		(pad "P18" thru_hole circle
			(at -2.70002 35.56)
			(size 1.1684 1.1684)
			(drill 0.762)
			(layers "*.Cu" "*.Mask")
			(remove_unused_layers no)
			(net "P12V")
			(clearance 0.0508)
			(thermal_gap 0.0508)
		)
		(pad "P19" thru_hole circle
			(at -2.70002 33.02)
			(size 1.1684 1.1684)
			(drill 0.762)
			(layers "*.Cu" "*.Mask")
			(remove_unused_layers no)
			(net "P12V")
			(clearance 0.0508)
			(thermal_gap 0.0508)
		)
		(pad "P20" thru_hole circle
			(at -2.70002 30.48)
			(size 1.1684 1.1684)
			(drill 0.762)
			(layers "*.Cu" "*.Mask")
			(remove_unused_layers no)
			(net "P12V")
			(clearance 0.0508)
			(thermal_gap 0.0508)
		)
		(pad "P21" thru_hole circle
			(at -2.70002 27.94)
			(size 1.1684 1.1684)
			(drill 0.762)
			(layers "*.Cu" "*.Mask")
			(remove_unused_layers no)
			(net "P12V")
			(clearance 0.0508)
			(thermal_gap 0.0508)
		)
		(pad "P22" thru_hole circle
			(at -2.70002 25.4)
			(size 1.1684 1.1684)
			(drill 0.762)
			(layers "*.Cu" "*.Mask")
			(remove_unused_layers no)
			(net "P12V")
			(clearance 0.0508)
			(thermal_gap 0.0508)
		)
		(pad "P23" thru_hole circle
			(at -2.70002 22.86)
			(size 1.1684 1.1684)
			(drill 0.762)
			(layers "*.Cu" "*.Mask")
			(remove_unused_layers no)
			(net "P12V")
			(clearance 0.0508)
			(thermal_gap 0.0508)
		)
		(pad "P24" thru_hole circle
			(at -2.70002 20.32)
			(size 1.1684 1.1684)
			(drill 0.762)
			(layers "*.Cu" "*.Mask")
			(remove_unused_layers no)
			(net "P12V")
			(clearance 0.0508)
			(thermal_gap 0.0508)
		)
		(pad "P25" thru_hole circle
			(at -2.70002 17.78)
			(size 1.1684 1.1684)
			(drill 0.762)
			(layers "*.Cu" "*.Mask")
			(remove_unused_layers no)
			(net "GND")
			(clearance 0.0508)
			(thermal_gap 0.0508)
		)
		(pad "P26" thru_hole circle
			(at -2.70002 15.24)
			(size 1.1684 1.1684)
			(drill 0.762)
			(layers "*.Cu" "*.Mask")
			(remove_unused_layers no)
			(net "GND")
			(clearance 0.0508)
			(thermal_gap 0.0508)
		)
		(pad "P27" thru_hole circle
			(at -2.70002 12.7)
			(size 1.1684 1.1684)
			(drill 0.762)
			(layers "*.Cu" "*.Mask")
			(remove_unused_layers no)
			(net "GND")
			(clearance 0.0508)
			(thermal_gap 0.0508)
		)
		(pad "P28" thru_hole circle
			(at -2.70002 10.16)
			(size 1.1684 1.1684)
			(drill 0.762)
			(layers "*.Cu" "*.Mask")
			(remove_unused_layers no)
			(net "GND")
			(clearance 0.0508)
			(thermal_gap 0.0508)
		)
		(pad "P29" thru_hole circle
			(at -2.70002 7.62)
			(size 1.1684 1.1684)
			(drill 0.762)
			(layers "*.Cu" "*.Mask")
			(remove_unused_layers no)
			(net "GND")
			(clearance 0.0508)
			(thermal_gap 0.0508)
		)
		(pad "P30" thru_hole circle
			(at -2.70002 5.08)
			(size 1.1684 1.1684)
			(drill 0.762)
			(layers "*.Cu" "*.Mask")
			(remove_unused_layers no)
			(net "GND")
			(clearance 0.0508)
			(thermal_gap 0.0508)
		)
		(pad "P31" thru_hole circle
			(at -2.70002 2.54)
			(size 1.1684 1.1684)
			(drill 0.762)
			(layers "*.Cu" "*.Mask")
			(remove_unused_layers no)
			(net "GND")
			(clearance 0.0508)
			(thermal_gap 0.0508)
		)
		(pad "P32" thru_hole circle
			(at -2.70002 0)
			(size 1.1684 1.1684)
			(drill 0.762)
			(layers "*.Cu" "*.Mask")
			(remove_unused_layers no)
			(net "GND")
			(clearance 0.0508)
			(thermal_gap 0.0508)
		)
		(pad "S1" thru_hole circle
			(at 0.55499 41.60012)
			(size 1.1684 1.1684)
			(drill 0.762)
			(layers "*.Cu" "*.Mask")
			(remove_unused_layers no)
			(net "T1_BLAD1_TXD")
			(clearance 0.0508)
			(thermal_gap 0.0508)
		)
		(pad "S2" thru_hole circle
			(at -0.71501 42.87012)
			(size 1.1684 1.1684)
			(drill 0.762)
			(layers "*.Cu" "*.Mask")
			(remove_unused_layers no)
			(net "T1_BLAD1_RXD")
			(clearance 0.0508)
			(thermal_gap 0.0508)
		)
		(pad "S3" thru_hole circle
			(at 0.55499 44.14012)
			(size 1.1684 1.1684)
			(drill 0.762)
			(layers "*.Cu" "*.Mask")
			(remove_unused_layers no)
			(net "T1_BLAD1_EN")
			(clearance 0.0508)
			(thermal_gap 0.0508)
		)
		(pad "S4" thru_hole circle
			(at -0.71501 45.41012)
			(size 1.1684 1.1684)
			(drill 0.762)
			(layers "*.Cu" "*.Mask")
			(remove_unused_layers no)
			(net "B1_PSU_ALERT_N")
			(clearance 0.0508)
			(thermal_gap 0.0508)
		)
		(pad "S5" thru_hole circle
			(at 0.55499 46.68012)
			(size 1.1684 1.1684)
			(drill 0.762)
			(layers "*.Cu" "*.Mask")
			(remove_unused_layers no)
			(net "T1_BLAD2_TXD")
			(clearance 0.0508)
			(thermal_gap 0.0508)
		)
		(pad "S6" thru_hole circle
			(at -0.71501 47.95012)
			(size 1.1684 1.1684)
			(drill 0.762)
			(layers "*.Cu" "*.Mask")
			(remove_unused_layers no)
			(net "T1_BLAD2_RXD")
			(clearance 0.0508)
			(thermal_gap 0.0508)
		)
		(pad "S7" thru_hole circle
			(at -3.25501 47.95012)
			(size 1.1684 1.1684)
			(drill 0.762)
			(layers "*.Cu" "*.Mask")
			(remove_unused_layers no)
			(net "T1_BLAD4_RXD")
			(clearance 0.0508)
			(thermal_gap 0.0508)
		)
		(pad "S8" thru_hole circle
			(at -1.98501 46.68012)
			(size 1.1684 1.1684)
			(drill 0.762)
			(layers "*.Cu" "*.Mask")
			(remove_unused_layers no)
			(net "T1_BLAD4_TXD")
			(clearance 0.0508)
			(thermal_gap 0.0508)
		)
		(pad "S9" thru_hole circle
			(at -3.25501 45.41012)
			(size 1.1684 1.1684)
			(drill 0.762)
			(layers "*.Cu" "*.Mask")
			(remove_unused_layers no)
			(net "B2_PSU_ALERT_N")
			(clearance 0.0508)
			(thermal_gap 0.0508)
		)
		(pad "S10" thru_hole circle
			(at -1.98501 44.14012)
			(size 1.1684 1.1684)
			(drill 0.762)
			(layers "*.Cu" "*.Mask")
			(remove_unused_layers no)
			(net "T1_BLAD3_EN")
			(clearance 0.0508)
			(thermal_gap 0.0508)
		)
		(pad "S11" thru_hole circle
			(at -3.25501 42.87012)
			(size 1.1684 1.1684)
			(drill 0.762)
			(layers "*.Cu" "*.Mask")
			(remove_unused_layers no)
			(net "T1_BLAD3_RXD")
			(clearance 0.0508)
			(thermal_gap 0.0508)
		)
		(pad "S12" thru_hole circle
			(at -1.98501 41.60012)
			(size 1.1684 1.1684)
			(drill 0.762)
			(layers "*.Cu" "*.Mask")
			(remove_unused_layers no)
			(net "T1_BLAD3_TXD")
			(clearance 0.0508)
			(thermal_gap 0.0508)
		)
	)
)
